(kicad_pcb
	(version 20260206)
	(generator "pcbnew")
	(generator_version "10.0")
	(general
		(thickness 1.6)
		(legacy_teardrops no)
	)
	(paper "A4")
	(title_block
		(title "peb — Lightning_PEB_BRD.brd")
		(comment 1 "Lightning (Wiwynn / Facebook NVMe JBOF) / footprints 140-147 of 2563")
	)
	(layers
		(0 "F.Cu" signal "TOP")
		(4 "In1.Cu" signal "L2GND")
		(6 "In2.Cu" signal "L3")
		(8 "In3.Cu" signal "L4VCC")
		(10 "In4.Cu" signal "L5VCC")
		(12 "In5.Cu" signal "L6")
		(14 "In6.Cu" signal "L7GND")
		(2 "B.Cu" signal "BOTTOM")
		(9 "F.Adhes" user "F.Adhesive")
		(11 "B.Adhes" user "B.Adhesive")
		(13 "F.Paste" user "Package Geometry/Pastemask Top")
		(15 "B.Paste" user "Package Geometry/Pastemask Bottom")
		(5 "F.SilkS" user "Ref Des/Silkscreen Top")
		(7 "B.SilkS" user "Ref Des/Silkscreen Bottom")
		(1 "F.Mask" user "Board Geometry/Soldermask Top")
		(3 "B.Mask" user "Board Geometry/Soldermask Bottom")
		(17 "Dwgs.User" user "User.Drawings")
		(19 "Cmts.User" user "User.Comments")
		(21 "Eco1.User" user "User.Eco1")
		(23 "Eco2.User" user "User.Eco2")
		(25 "Edge.Cuts" user "Board Geometry/Outline")
		(27 "Margin" user)
		(31 "F.CrtYd" user "Package Geometry/Place Bound Top")
		(29 "B.CrtYd" user "Package Geometry/Place Bound Bottom")
		(35 "F.Fab" user "Ref Des/Assembly Top")
		(33 "B.Fab" user "Ref Des/Assembly Bottom")
	)
	(footprint ""
		(layer "F.Cu")
		(at 39.5732 -102.1588 90)
		(property "Reference" "R602"
			(at 0 0 90)
			(layer "F.SilkS")
			(hide yes)
			(effects
				(font
					(size 1.27 1.27)
				)
			)
		)
		(property "Value" "10KR2F-2-GP"
			(at 0.064008 -3.993896 90)
			(unlocked yes)
			(layer "F.Fab")
			(hide yes)
			(effects
				(font
					(size 1.016 1.016)
					(thickness 0.1524)
				)
			)
		)
		(property "Device Type" "R402H16"
			(at 0.064008 -5.517896 90)
			(unlocked yes)
			(layer "F.Fab")
			(hide yes)
			(effects
				(font
					(size 1.016 1.016)
					(thickness 0.1524)
				)
			)
		)
		(duplicate_pad_numbers_are_jumpers no)
		(fp_line
			(start 0.508 -0.9398)
			(end -0.508 -0.9398)
			(stroke
				(width 0.1524)
				(type default)
			)
			(layer "F.SilkS")
		)
		(fp_line
			(start -0.508 -0.9398)
			(end -0.508 0.9398)
			(stroke
				(width 0.1524)
				(type default)
			)
			(layer "F.SilkS")
		)
		(fp_rect
			(start -0.508 0.9398)
			(end 0.508 -0.9398)
			(stroke
				(width 0)
				(type default)
			)
			(fill no)
			(layer "F.CrtYd")
		)
		(fp_rect
			(start -0.508 0.9398)
			(end 0.508 -0.9398)
			(stroke
				(width 0)
				(type default)
			)
			(fill no)
			(layer "F.Fab")
		)
		(pad "1" smd custom
			(at 0 -0.4445 90)
			(size 0.1397 0.1397)
			(layers "F.Cu" "F.Mask" "F.Paste")
			(net "BUS_SW_OE#")
			(options
				(clearance outline)
				(anchor circle)
			)
			(primitives
				(gr_poly
					(pts
						(arc
							(start -0.1778 -0.2794)
							(mid -0.249642 -0.249642)
							(end -0.2794 -0.1778)
						)
						(arc
							(start -0.2794 0.1778)
							(mid -0.249642 0.249642)
							(end -0.1778 0.2794)
						)
						(arc
							(start 0.1778 0.2794)
							(mid 0.249642 0.249642)
							(end 0.2794 0.1778)
						)
						(arc
							(start 0.2794 -0.1778)
							(mid 0.249642 -0.249642)
							(end 0.1778 -0.2794)
						)
					)
					(width 0)
					(fill yes)
				)
			)
		)
		(pad "2" smd custom
			(at 0 0.4445 90)
			(size 0.1397 0.1397)
			(layers "F.Cu" "F.Mask" "F.Paste")
			(net "GND")
			(options
				(clearance outline)
				(anchor circle)
			)
			(primitives
				(gr_poly
					(pts
						(arc
							(start -0.1778 -0.2794)
							(mid -0.249642 -0.249642)
							(end -0.2794 -0.1778)
						)
						(arc
							(start -0.2794 0.1778)
							(mid -0.249642 0.249642)
							(end -0.1778 0.2794)
						)
						(arc
							(start 0.1778 0.2794)
							(mid 0.249642 0.249642)
							(end 0.2794 0.1778)
						)
						(arc
							(start 0.2794 -0.1778)
							(mid 0.249642 -0.249642)
							(end 0.1778 -0.2794)
						)
					)
					(width 0)
					(fill yes)
				)
			)
		)
	)
	(footprint ""
		(layer "F.Cu")
		(at 313.19216 -212.420454 180)
		(property "Reference" "C70"
			(at 0 0 180)
			(layer "F.SilkS")
			(hide yes)
			(effects
				(font
					(size 1.27 1.27)
				)
			)
		)
		(property "Value" "SCD22U10V2KX-1GP"
			(at 1.1811 -2.7051 180)
			(unlocked yes)
			(layer "F.Fab")
			(hide yes)
			(effects
				(font
					(size 1.016 1.016)
					(thickness 0.1524)
				)
			)
		)
		(property "Device Type" "C402H22"
			(at 1.1811 -4.2291 180)
			(unlocked yes)
			(layer "F.Fab")
			(hide yes)
			(effects
				(font
					(size 1.016 1.016)
					(thickness 0.1524)
				)
			)
		)
		(duplicate_pad_numbers_are_jumpers no)
		(fp_rect
			(start -0.4318 0.9525)
			(end 0.4318 -0.9525)
			(stroke
				(width 0)
				(type default)
			)
			(fill no)
			(layer "F.CrtYd")
		)
		(fp_rect
			(start -0.4318 0.9525)
			(end 0.4318 -0.9525)
			(stroke
				(width 0)
				(type default)
			)
			(fill no)
			(layer "F.Fab")
		)
		(pad "1" smd custom
			(at 0 -0.4445 180)
			(size 0.1524 0.1524)
			(layers "F.Cu" "F.Mask" "F.Paste")
			(net "PCIE_TX_CAP_P24")
			(options
				(clearance outline)
				(anchor circle)
			)
			(primitives
				(gr_poly
					(pts
						(arc
							(start 0.3048 -0.2032)
							(mid 0.275042 -0.275042)
							(end 0.2032 -0.3048)
						)
						(arc
							(start -0.2032 -0.3048)
							(mid -0.275042 -0.275042)
							(end -0.3048 -0.2032)
						)
						(arc
							(start -0.3048 0.2032)
							(mid -0.275042 0.275042)
							(end -0.2032 0.3048)
						)
						(arc
							(start 0.2032 0.3048)
							(mid 0.275042 0.275042)
							(end 0.3048 0.2032)
						)
					)
					(width 0)
					(fill yes)
				)
			)
		)
		(pad "2" smd custom
			(at 0 0.4445 180)
			(size 0.1524 0.1524)
			(layers "F.Cu" "F.Mask" "F.Paste")
			(net "PCIE_TX_P24")
			(options
				(clearance outline)
				(anchor circle)
			)
			(primitives
				(gr_poly
					(pts
						(arc
							(start 0.3048 -0.2032)
							(mid 0.275042 -0.275042)
							(end 0.2032 -0.3048)
						)
						(arc
							(start -0.2032 -0.3048)
							(mid -0.275042 -0.275042)
							(end -0.3048 -0.2032)
						)
						(arc
							(start -0.3048 0.2032)
							(mid -0.275042 0.275042)
							(end -0.2032 0.3048)
						)
						(arc
							(start 0.2032 0.3048)
							(mid 0.275042 0.275042)
							(end 0.3048 0.2032)
						)
					)
					(width 0)
					(fill yes)
				)
			)
		)
	)
	(footprint ""
		(layer "F.Cu")
		(at 85.09 -46.609 180)
		(property "Reference" "PC40"
			(at 0 0 180)
			(layer "F.SilkS")
			(hide yes)
			(effects
				(font
					(size 1.27 1.27)
				)
			)
		)
		(property "Value" "SC10U6D3V5KX-4GP"
			(at -0.0762 -6.1214 180)
			(unlocked yes)
			(layer "F.Fab")
			(hide yes)
			(effects
				(font
					(size 1.016 1.016)
					(thickness 0.1524)
				)
			)
		)
		(property "Device Type" "C805H58"
			(at -0.0762 -8.1534 180)
			(unlocked yes)
			(layer "F.Fab")
			(hide yes)
			(effects
				(font
					(size 1.016 1.016)
					(thickness 0.1524)
				)
			)
		)
		(duplicate_pad_numbers_are_jumpers no)
		(fp_line
			(start 0.635 0)
			(end -0.635 0)
			(stroke
				(width 0.508)
				(type default)
			)
			(layer "F.SilkS")
		)
		(fp_rect
			(start -0.9652 1.778)
			(end 0.9652 -1.778)
			(stroke
				(width 0)
				(type default)
			)
			(fill no)
			(layer "F.CrtYd")
		)
		(fp_poly
			(pts
				(xy -0.9652 -1.778) (xy 0.9652 -1.778) (xy 0.9652 1.778) (xy -0.9652 1.778)
			)
			(stroke
				(width 0)
				(type default)
			)
			(fill no)
			(layer "F.Fab")
		)
		(pad "1" smd rect
			(at 0 -0.9652 180)
			(size 1.397 1.143)
			(layers "F.Cu" "F.Mask" "F.Paste")
			(net "P3V3_PWR")
		)
		(pad "2" smd rect
			(at 0 0.9652 180)
			(size 1.397 1.143)
			(layers "F.Cu" "F.Mask" "F.Paste")
			(net "GND")
		)
	)
	(footprint ""
		(layer "F.Cu")
		(at 130.677158 -74.60996 90)
		(property "Reference" "C723"
			(at 0 0 90)
			(layer "F.SilkS")
			(hide yes)
			(effects
				(font
					(size 1.27 1.27)
				)
			)
		)
		(property "Value" "SC10U16V5KX-1-GP"
			(at -0.0762 -6.1214 90)
			(unlocked yes)
			(layer "F.Fab")
			(hide yes)
			(effects
				(font
					(size 1.016 1.016)
					(thickness 0.1524)
				)
			)
		)
		(property "Device Type" "C805H54"
			(at -0.0762 -8.1534 90)
			(unlocked yes)
			(layer "F.Fab")
			(hide yes)
			(effects
				(font
					(size 1.016 1.016)
					(thickness 0.1524)
				)
			)
		)
		(duplicate_pad_numbers_are_jumpers no)
		(fp_line
			(start 0.635 0)
			(end -0.635 0)
			(stroke
				(width 0.508)
				(type default)
			)
			(layer "F.SilkS")
		)
		(fp_rect
			(start -0.9652 1.778)
			(end 0.9652 -1.778)
			(stroke
				(width 0)
				(type default)
			)
			(fill no)
			(layer "F.CrtYd")
		)
		(fp_poly
			(pts
				(xy -0.9652 -1.778) (xy 0.9652 -1.778) (xy 0.9652 1.778) (xy -0.9652 1.778)
			)
			(stroke
				(width 0)
				(type default)
			)
			(fill no)
			(layer "F.Fab")
		)
		(pad "1" smd rect
			(at 0 -0.9652 90)
			(size 1.397 1.143)
			(layers "F.Cu" "F.Mask" "F.Paste")
			(net "P1V8_STBY")
		)
		(pad "2" smd rect
			(at 0 0.9652 90)
			(size 1.397 1.143)
			(layers "F.Cu" "F.Mask" "F.Paste")
			(net "GND")
		)
	)
	(footprint ""
		(layer "F.Cu")
		(at 35.792918 -84.64931 90)
		(property "Reference" "Q46"
			(at 0 0 90)
			(layer "F.SilkS")
			(hide yes)
			(effects
				(font
					(size 1.27 1.27)
				)
			)
		)
		(property "Value" "DSS4240T-7-GP"
			(at 0.10287 -10.29843 90)
			(unlocked yes)
			(layer "F.Fab")
			(hide yes)
			(effects
				(font
					(size 1.016 1.016)
					(thickness 0.1524)
				)
			)
		)
		(property "Device Type" "SOT23CBE2D4H44"
			(at 0.10287 -12.20343 90)
			(unlocked yes)
			(layer "F.Fab")
			(hide yes)
			(effects
				(font
					(size 1.016 1.016)
					(thickness 0.1524)
				)
			)
		)
		(duplicate_pad_numbers_are_jumpers no)
		(fp_line
			(start 1.651 -1.778)
			(end -1.651 -1.778)
			(stroke
				(width 0.1524)
				(type default)
			)
			(layer "F.SilkS")
		)
		(fp_line
			(start -1.651 -1.778)
			(end -1.651 1.778)
			(stroke
				(width 0.1524)
				(type default)
			)
			(layer "F.SilkS")
		)
		(fp_line
			(start 1.651 1.778)
			(end 1.651 -1.778)
			(stroke
				(width 0.1524)
				(type default)
			)
			(layer "F.SilkS")
		)
		(fp_line
			(start -1.651 1.778)
			(end 1.651 1.778)
			(stroke
				(width 0.1524)
				(type default)
			)
			(layer "F.SilkS")
		)
		(fp_poly
			(pts
				(xy -1.778 1.8796) (xy -1.778 -1.8796) (xy 1.778 -1.8796) (xy 1.778 1.8796)
			)
			(stroke
				(width 0)
				(type default)
			)
			(fill no)
			(layer "F.CrtYd")
		)
		(fp_poly
			(pts
				(xy -1.778 1.8796) (xy -1.778 -1.8796) (xy 1.778 -1.8796) (xy 1.778 1.8796)
			)
			(stroke
				(width 0)
				(type default)
			)
			(fill no)
			(layer "F.Fab")
		)
		(pad "B" smd custom
			(at -0.98425 0.9525 90)
			(size 0.1905 0.1905)
			(layers "F.Cu" "F.Mask" "F.Paste")
			(net "Q46_G")
			(options
				(clearance outline)
				(anchor circle)
			)
			(primitives
				(gr_poly
					(pts
						(arc
							(start -0.1778 0.5715)
							(mid -0.321484 0.511984)
							(end -0.381 0.3683)
						)
						(arc
							(start -0.381 -0.3683)
							(mid -0.321484 -0.511984)
							(end -0.1778 -0.5715)
						)
						(arc
							(start 0.1778 -0.5715)
							(mid 0.321484 -0.511984)
							(end 0.381 -0.3683)
						)
						(arc
							(start 0.381 0.3683)
							(mid 0.321484 0.511984)
							(end 0.1778 0.5715)
						)
					)
					(width 0)
					(fill yes)
				)
			)
		)
		(pad "C" smd custom
			(at 0 -0.9525 90)
			(size 0.1905 0.1905)
			(layers "F.Cu" "F.Mask" "F.Paste")
			(net "Q46_D")
			(options
				(clearance outline)
				(anchor circle)
			)
			(primitives
				(gr_poly
					(pts
						(arc
							(start -0.1778 0.5715)
							(mid -0.321484 0.511984)
							(end -0.381 0.3683)
						)
						(arc
							(start -0.381 -0.3683)
							(mid -0.321484 -0.511984)
							(end -0.1778 -0.5715)
						)
						(arc
							(start 0.1778 -0.5715)
							(mid 0.321484 -0.511984)
							(end 0.381 -0.3683)
						)
						(arc
							(start 0.381 0.3683)
							(mid 0.321484 0.511984)
							(end 0.1778 0.5715)
						)
					)
					(width 0)
					(fill yes)
				)
			)
		)
		(pad "E" smd custom
			(at 0.98425 0.9525 90)
			(size 0.1905 0.1905)
			(layers "F.Cu" "F.Mask" "F.Paste")
			(net "GND")
			(options
				(clearance outline)
				(anchor circle)
			)
			(primitives
				(gr_poly
					(pts
						(arc
							(start -0.1778 0.5715)
							(mid -0.321484 0.511984)
							(end -0.381 0.3683)
						)
						(arc
							(start -0.381 -0.3683)
							(mid -0.321484 -0.511984)
							(end -0.1778 -0.5715)
						)
						(arc
							(start 0.1778 -0.5715)
							(mid 0.321484 -0.511984)
							(end 0.381 -0.3683)
						)
						(arc
							(start 0.381 0.3683)
							(mid 0.321484 0.511984)
							(end 0.1778 0.5715)
						)
					)
					(width 0)
					(fill yes)
				)
			)
		)
	)
	(footprint ""
		(layer "F.Cu")
		(at 45.053758 -117.284246)
		(property "Reference" "TP94"
			(at 0 0 0)
			(layer "F.SilkS")
			(hide yes)
			(effects
				(font
					(size 1.27 1.27)
				)
			)
		)
		(property "Value" "TPAD28-2-GP"
			(at -0.0127 -1.6637 0)
			(unlocked yes)
			(layer "F.Fab")
			(hide yes)
			(effects
				(font
					(size 1.016 1.016)
					(thickness 0.1524)
				)
			)
		)
		(property "Device Type" "TPAD28"
			(at -0.0127 -3.1877 0)
			(unlocked yes)
			(layer "F.Fab")
			(hide yes)
			(effects
				(font
					(size 1.016 1.016)
					(thickness 0.1524)
				)
			)
		)
		(duplicate_pad_numbers_are_jumpers no)
		(fp_poly
			(pts
				(arc
					(start 0.3556 0)
					(mid -0.3556 0)
					(end 0.3556 0)
				)
			)
			(stroke
				(width 0)
				(type default)
			)
			(fill no)
			(layer "F.CrtYd")
		)
		(fp_poly
			(pts
				(arc
					(start 0.6096 0)
					(mid -0.6096 0)
					(end 0.6096 0)
				)
			)
			(stroke
				(width 0)
				(type default)
			)
			(fill no)
			(layer "F.Fab")
		)
		(pad "1" smd circle
			(at 0 0)
			(size 0.7112 0.7112)
			(layers "F.Cu" "F.Mask" "F.Paste")
			(net "TP_GPIOH5")
		)
	)
	(footprint ""
		(layer "F.Cu")
		(at 65.8368 -112.5982 90)
		(property "Reference" "R438"
			(at 0 0 90)
			(layer "F.SilkS")
			(hide yes)
			(effects
				(font
					(size 1.27 1.27)
				)
			)
		)
		(property "Value" "4K7R2F-GP"
			(at 0.064008 -3.993896 90)
			(unlocked yes)
			(layer "F.Fab")
			(hide yes)
			(effects
				(font
					(size 1.016 1.016)
					(thickness 0.1524)
				)
			)
		)
		(property "Device Type" "R402H16"
			(at 0.064008 -5.517896 90)
			(unlocked yes)
			(layer "F.Fab")
			(hide yes)
			(effects
				(font
					(size 1.016 1.016)
					(thickness 0.1524)
				)
			)
		)
		(duplicate_pad_numbers_are_jumpers no)
		(fp_line
			(start 0.508 -0.9398)
			(end -0.508 -0.9398)
			(stroke
				(width 0.1524)
				(type default)
			)
			(layer "F.SilkS")
		)
		(fp_line
			(start -0.508 -0.9398)
			(end -0.508 0.9398)
			(stroke
				(width 0.1524)
				(type default)
			)
			(layer "F.SilkS")
		)
		(fp_rect
			(start -0.508 0.9398)
			(end 0.508 -0.9398)
			(stroke
				(width 0)
				(type default)
			)
			(fill no)
			(layer "F.CrtYd")
		)
		(fp_rect
			(start -0.508 0.9398)
			(end 0.508 -0.9398)
			(stroke
				(width 0)
				(type default)
			)
			(fill no)
			(layer "F.Fab")
		)
		(pad "1" smd custom
			(at 0 -0.4445 90)
			(size 0.1397 0.1397)
			(layers "F.Cu" "F.Mask" "F.Paste")
			(net "BMC_I2C11_MINI5_SCL_S")
			(options
				(clearance outline)
				(anchor circle)
			)
			(primitives
				(gr_poly
					(pts
						(arc
							(start -0.1778 -0.2794)
							(mid -0.249642 -0.249642)
							(end -0.2794 -0.1778)
						)
						(arc
							(start -0.2794 0.1778)
							(mid -0.249642 0.249642)
							(end -0.1778 0.2794)
						)
						(arc
							(start 0.1778 0.2794)
							(mid 0.249642 0.249642)
							(end 0.2794 0.1778)
						)
						(arc
							(start 0.2794 -0.1778)
							(mid 0.249642 -0.249642)
							(end 0.1778 -0.2794)
						)
					)
					(width 0)
					(fill yes)
				)
			)
		)
		(pad "2" smd custom
			(at 0 0.4445 90)
			(size 0.1397 0.1397)
			(layers "F.Cu" "F.Mask" "F.Paste")
			(net "P3V3_STBY")
			(options
				(clearance outline)
				(anchor circle)
			)
			(primitives
				(gr_poly
					(pts
						(arc
							(start -0.1778 -0.2794)
							(mid -0.249642 -0.249642)
							(end -0.2794 -0.1778)
						)
						(arc
							(start -0.2794 0.1778)
							(mid -0.249642 0.249642)
							(end -0.1778 0.2794)
						)
						(arc
							(start 0.1778 0.2794)
							(mid 0.249642 0.249642)
							(end 0.2794 0.1778)
						)
						(arc
							(start 0.2794 -0.1778)
							(mid 0.249642 -0.249642)
							(end 0.1778 -0.2794)
						)
					)
					(width 0)
					(fill yes)
				)
			)
		)
	)
	(footprint ""
		(layer "F.Cu")
		(at 47.244 -194.564)
		(property "Reference" "C707"
			(at 0 0 0)
			(layer "F.SilkS")
			(hide yes)
			(effects
				(font
					(size 1.27 1.27)
				)
			)
		)
		(property "Value" "SCD01U50V2KX-1GP"
			(at 1.1811 -2.7051 0)
			(unlocked yes)
			(layer "F.Fab")
			(hide yes)
			(effects
				(font
					(size 1.016 1.016)
					(thickness 0.1524)
				)
			)
		)
		(property "Device Type" "C402H22"
			(at 1.1811 -4.2291 0)
			(unlocked yes)
			(layer "F.Fab")
			(hide yes)
			(effects
				(font
					(size 1.016 1.016)
					(thickness 0.1524)
				)
			)
		)
		(duplicate_pad_numbers_are_jumpers no)
		(fp_rect
			(start -0.4318 0.9525)
			(end 0.4318 -0.9525)
			(stroke
				(width 0)
				(type default)
			)
			(fill no)
			(layer "F.CrtYd")
		)
		(fp_rect
			(start -0.4318 0.9525)
			(end 0.4318 -0.9525)
			(stroke
				(width 0)
				(type default)
			)
			(fill no)
			(layer "F.Fab")
		)
		(pad "1" smd custom
			(at 0 -0.4445)
			(size 0.1524 0.1524)
			(layers "F.Cu" "F.Mask" "F.Paste")
			(net "P3V3_STBY")
			(options
				(clearance outline)
				(anchor circle)
			)
			(primitives
				(gr_poly
					(pts
						(arc
							(start 0.3048 -0.2032)
							(mid 0.275042 -0.275042)
							(end 0.2032 -0.3048)
						)
						(arc
							(start -0.2032 -0.3048)
							(mid -0.275042 -0.275042)
							(end -0.3048 -0.2032)
						)
						(arc
							(start -0.3048 0.2032)
							(mid -0.275042 0.275042)
							(end -0.2032 0.3048)
						)
						(arc
							(start 0.2032 0.3048)
							(mid 0.275042 0.275042)
							(end 0.3048 0.2032)
						)
					)
					(width 0)
					(fill yes)
				)
			)
		)
		(pad "2" smd custom
			(at 0 0.4445)
			(size 0.1524 0.1524)
			(layers "F.Cu" "F.Mask" "F.Paste")
			(net "GND")
			(options
				(clearance outline)
				(anchor circle)
			)
			(primitives
				(gr_poly
					(pts
						(arc
							(start 0.3048 -0.2032)
							(mid 0.275042 -0.275042)
							(end 0.2032 -0.3048)
						)
						(arc
							(start -0.2032 -0.3048)
							(mid -0.275042 -0.275042)
							(end -0.3048 -0.2032)
						)
						(arc
							(start -0.3048 0.2032)
							(mid -0.275042 0.275042)
							(end -0.2032 0.3048)
						)
						(arc
							(start 0.2032 0.3048)
							(mid 0.275042 0.275042)
							(end 0.3048 0.2032)
						)
					)
					(width 0)
					(fill yes)
				)
			)
		)
	)
)
